# TIMECARD (Time Appliance Project (Time Card)) — schematic netlist excerpt (pin names and nets, part order shuffled) for the footprints in the layout excerpt that follows; sources: Cadence DE-HDL packaged netlist, KiCad conversion of R4006-B0001-02_R01.brd

R493  RESISTOR  0OHM -  pkg SMC_0402R_H016  page 23 : \1\ = UNNAMED_12_CAPACITOR_I321_2 ; \2\ = UNNAMED_12_74HCT2G125DPTSSOP8_3
R89  RESISTOR  100OHM 1%  pkg SMC_0402R_H016  page 21 : \1\ = R_MAC_PPS_IN1P ; \2\ = R_MAC_PPS_IN1N

(kicad_pcb
	(version 20260206)
	(generator "pcbnew")
	(generator_version "10.0")
	(general
		(thickness 1.6)
		(legacy_teardrops no)
	)
	(paper "A4")
	(title_block
		(title "timecard-production-celestica-r4006 — R4006-B0001-02_R01.brd")
		(comment 1 "Time Appliance Project (Time Card) / footprints 750-751 of 1113")
	)
	(layers
		(0 "F.Cu" signal "TOP")
		(4 "In1.Cu" signal "L02_GND1")
		(6 "In2.Cu" signal "L03_SIG1")
		(8 "In3.Cu" signal "L04_GND2")
		(10 "In4.Cu" signal "L05_VCC1")
		(12 "In5.Cu" signal "L06_VCC2")
		(14 "In6.Cu" signal "L07_GND3")
		(16 "In7.Cu" signal "L08_SIG2")
		(18 "In8.Cu" signal "L09_GND4")
		(2 "B.Cu" signal "BOTTOM")
		(9 "F.Adhes" user "F.Adhesive")
		(11 "B.Adhes" user "B.Adhesive")
		(13 "F.Paste" user "Package Geometry/Pastemask Top")
		(15 "B.Paste" user "Package Geometry/Pastemask Bottom")
		(5 "F.SilkS" user "Ref Des/Silkscreen Top")
		(7 "B.SilkS" user "Ref Des/Silkscreen Bottom")
		(1 "F.Mask" user "Board Geometry/Soldermask Top")
		(3 "B.Mask" user "Board Geometry/Soldermask Bottom")
		(17 "Dwgs.User" user "User.Drawings")
		(19 "Cmts.User" user "User.Comments")
		(21 "Eco1.User" user "User.Eco1")
		(23 "Eco2.User" user "User.Eco2")
		(25 "Edge.Cuts" user "Board Geometry/Outline")
		(27 "Margin" user)
		(31 "F.CrtYd" user "Package Geometry/Place Bound Top")
		(29 "B.CrtYd" user "Package Geometry/Place Bound Bottom")
		(35 "F.Fab" user "Ref Des/Assembly Top")
		(33 "B.Fab" user "Ref Des/Assembly Bottom")
	)
	(footprint ""
		(layer "B.Cu")
		(at 71.5645 -49.403 180)
		(property "Reference" "R89"
			(at 2.3495 -0.03937 0)
			(unlocked yes)
			(layer "B.SilkS")
			(effects
				(font
					(size 0.7874 0.5842)
					(thickness 0.1524)
				)
				(justify mirror)
			)
		)
		(property "Value" "VAL*"
			(at -0.02032 2.13233 180)
			(unlocked yes)
			(layer "B.Fab")
			(hide yes)
			(effects
				(font
					(size 0.7874 0.5842)
					(thickness 0.1524)
				)
				(justify mirror)
			)
		)
		(property "Tolerance" "TOL*"
			(at -0.044704 3.05435 180)
			(unlocked yes)
			(layer "Cmts.User")
			(hide yes)
			(effects
				(font
					(size 0.7874 0.5842)
					(thickness 0.1524)
				)
				(justify mirror)
			)
		)
		(property "User Part Number" "PARTNUM*"
			(at -0.02032 4.024884 180)
			(unlocked yes)
			(layer "Cmts.User")
			(hide yes)
			(effects
				(font
					(size 0.7874 0.5842)
					(thickness 0.1524)
				)
				(justify mirror)
			)
		)
		(property "Device Type" "RESISTOR-G155-11000-01,100OHM,A"
			(at -0.008382 1.210564 180)
			(unlocked yes)
			(layer "B.Fab")
			(hide yes)
			(effects
				(font
					(size 0.7874 0.5842)
					(thickness 0.1524)
				)
				(justify mirror)
			)
		)
		(duplicate_pad_numbers_are_jumpers no)
		(fp_line
			(start 1.143 0.5588)
			(end -1.143 0.5588)
			(stroke
				(width 0.1)
				(type default)
			)
			(layer "B.SilkS")
		)
		(fp_line
			(start 1.143 -0.5588)
			(end 1.143 0.5588)
			(stroke
				(width 0.1)
				(type default)
			)
			(layer "B.SilkS")
		)
		(fp_line
			(start -1.143 0.5588)
			(end -1.143 -0.5588)
			(stroke
				(width 0.1)
				(type default)
			)
			(layer "B.SilkS")
		)
		(fp_line
			(start -1.143 -0.5588)
			(end 1.143 -0.5588)
			(stroke
				(width 0.1)
				(type default)
			)
			(layer "B.SilkS")
		)
		(fp_rect
			(start -1.143 0.5588)
			(end 1.143 -0.5588)
			(stroke
				(width 0)
				(type default)
			)
			(fill no)
			(layer "B.CrtYd")
		)
		(fp_line
			(start 0.508 0.3048)
			(end -0.508 0.3048)
			(stroke
				(width 0.1)
				(type default)
			)
			(layer "B.Fab")
		)
		(fp_line
			(start 0.508 -0.3048)
			(end 0.508 0.3048)
			(stroke
				(width 0.1)
				(type default)
			)
			(layer "B.Fab")
		)
		(fp_line
			(start -0.508 0.3048)
			(end -0.508 -0.3048)
			(stroke
				(width 0.1)
				(type default)
			)
			(layer "B.Fab")
		)
		(fp_line
			(start -0.508 -0.3048)
			(end 0.508 -0.3048)
			(stroke
				(width 0.1)
				(type default)
			)
			(layer "B.Fab")
		)
		(pad "1" smd rect
			(at 0.5334 0)
			(size 0.7112 0.6096)
			(layers "B.Cu" "B.Mask" "B.Paste")
			(net "R_MAC_PPS_IN1P")
		)
		(pad "2" smd rect
			(at -0.5334 0)
			(size 0.7112 0.6096)
			(layers "B.Cu" "B.Mask" "B.Paste")
			(net "R_MAC_PPS_IN1N")
		)
		(zone
			(layer "B.Cu")
			(hatch none 0.5)
			(connect_pads
				(clearance 0)
			)
			(min_thickness 0.25)
			(keepout
				(tracks allowed)
				(vias not_allowed)
				(pads allowed)
				(copperpour not_allowed)
				(footprints allowed)
			)
			(placement
				(enabled no)
				(sheetname "")
			)
			(fill
				(thermal_gap 0.5)
				(thermal_bridge_width 0.5)
				(island_removal_mode 0)
			)
			(polygon
				(pts
					(xy 71.6407 -49.7078) (xy 71.4883 -49.7078) (xy 71.4883 -49.0982) (xy 71.6407 -49.0982)
				)
			)
		)
	)
	(footprint ""
		(layer "B.Cu")
		(at 13.589 -22.987 90)
		(property "Reference" "R493"
			(at 0 0.98425 270)
			(unlocked yes)
			(layer "B.SilkS")
			(effects
				(font
					(size 0.635 0.4064)
					(thickness 0.1524)
				)
				(justify mirror)
			)
		)
		(property "Value" "VAL*"
			(at -0.02032 2.13233 90)
			(unlocked yes)
			(layer "B.Fab")
			(hide yes)
			(effects
				(font
					(size 0.7874 0.5842)
					(thickness 0.1524)
				)
				(justify mirror)
			)
		)
		(property "Tolerance" "TOL*"
			(at -0.044704 3.05435 90)
			(unlocked yes)
			(layer "Cmts.User")
			(hide yes)
			(effects
				(font
					(size 0.7874 0.5842)
					(thickness 0.1524)
				)
				(justify mirror)
			)
		)
		(property "User Part Number" "PARTNUM*"
			(at -0.02032 4.024884 90)
			(unlocked yes)
			(layer "Cmts.User")
			(hide yes)
			(effects
				(font
					(size 0.7874 0.5842)
					(thickness 0.1524)
				)
				(justify mirror)
			)
		)
		(property "Device Type" "RESISTOR-G155-100R0-J0,0OHM,-"
			(at -0.008382 1.210564 90)
			(unlocked yes)
			(layer "B.Fab")
			(hide yes)
			(effects
				(font
					(size 0.7874 0.5842)
					(thickness 0.1524)
				)
				(justify mirror)
			)
		)
		(duplicate_pad_numbers_are_jumpers no)
		(fp_line
			(start 1.143 -0.5588)
			(end 1.143 0.5588)
			(stroke
				(width 0.1)
				(type default)
			)
			(layer "B.SilkS")
		)
		(fp_line
			(start -1.143 -0.5588)
			(end 1.143 -0.5588)
			(stroke
				(width 0.1)
				(type default)
			)
			(layer "B.SilkS")
		)
		(fp_line
			(start 1.143 0.5588)
			(end -1.143 0.5588)
			(stroke
				(width 0.1)
				(type default)
			)
			(layer "B.SilkS")
		)
		(fp_line
			(start -1.143 0.5588)
			(end -1.143 -0.5588)
			(stroke
				(width 0.1)
				(type default)
			)
			(layer "B.SilkS")
		)
		(fp_poly
			(pts
				(xy 1.143 0.5588) (xy -1.143 0.5588) (xy -1.143 -0.5588) (xy 1.143 -0.5588)
			)
			(stroke
				(width 0)
				(type default)
			)
			(fill no)
			(layer "B.CrtYd")
		)
		(fp_line
			(start 0.508 -0.3048)
			(end 0.508 0.3048)
			(stroke
				(width 0.1)
				(type default)
			)
			(layer "B.Fab")
		)
		(fp_line
			(start -0.508 -0.3048)
			(end 0.508 -0.3048)
			(stroke
				(width 0.1)
				(type default)
			)
			(layer "B.Fab")
		)
		(fp_line
			(start 0.508 0.3048)
			(end -0.508 0.3048)
			(stroke
				(width 0.1)
				(type default)
			)
			(layer "B.Fab")
		)
		(fp_line
			(start -0.508 0.3048)
			(end -0.508 -0.3048)
			(stroke
				(width 0.1)
				(type default)
			)
			(layer "B.Fab")
		)
		(pad "1" smd rect
			(at 0.5334 0 270)
			(size 0.7112 0.6096)
			(layers "B.Cu" "B.Mask" "B.Paste")
			(net "UNNAMED_12_CAPACITOR_I321_2")
		)
		(pad "2" smd rect
			(at -0.5334 0 270)
			(size 0.7112 0.6096)
			(layers "B.Cu" "B.Mask" "B.Paste")
			(net "UNNAMED_12_74HCT2G125DPTSSOP8_3")
		)
		(zone
			(layer "B.Cu")
			(hatch none 0.5)
			(connect_pads
				(clearance 0)
			)
			(min_thickness 0.25)
			(keepout
				(tracks allowed)
				(vias not_allowed)
				(pads allowed)
				(copperpour not_allowed)
				(footprints allowed)
			)
			(placement
				(enabled no)
				(sheetname "")
			)
			(fill
				(thermal_gap 0.5)
				(thermal_bridge_width 0.5)
				(island_removal_mode 0)
			)
			(polygon
				(pts
					(xy 13.8938 -23.0632) (xy 13.2842 -23.0632) (xy 13.2842 -22.9108) (xy 13.8938 -22.9108)
				)
			)
		)
		(zone
			(layer "B.Cu")
			(hatch none 0.5)
			(connect_pads
				(clearance 0)
			)
			(min_thickness 0.25)
			(keepout
				(tracks not_allowed)
				(vias allowed)
				(pads allowed)
				(copperpour not_allowed)
				(footprints allowed)
			)
			(placement
				(enabled no)
				(sheetname "")
			)
			(fill
				(thermal_gap 0.5)
				(thermal_bridge_width 0.5)
				(island_removal_mode 0)
			)
			(polygon
				(pts
					(xy 13.8938 -23.0632) (xy 13.2842 -23.0632) (xy 13.2842 -22.9108) (xy 13.8938 -22.9108)
				)
			)
		)
	)
)
